(kicad_pcb
	(version 20260206)
	(generator "pcbnew")
	(generator_version "10.0")
	(general
		(thickness 1.6)
		(legacy_teardrops no)
	)
	(paper "A4")
	(title_block
		(title "Bryce Canyon_SCC_16316-1_OCP.brd")
		(comment 1 "Bryce Canyon / footprints 704-710 of 1561")
	)
	(layers
		(0 "F.Cu" signal "TOP")
		(4 "In1.Cu" signal "L2GND")
		(6 "In2.Cu" signal "L3")
		(8 "In3.Cu" signal "L4VCC")
		(10 "In4.Cu" signal "L5VCC")
		(12 "In5.Cu" signal "L6")
		(14 "In6.Cu" signal "L7GND")
		(2 "B.Cu" signal "BOTTOM")
		(9 "F.Adhes" user "F.Adhesive")
		(11 "B.Adhes" user "B.Adhesive")
		(13 "F.Paste" user "Package Geometry/Pastemask Top")
		(15 "B.Paste" user "Package Geometry/Pastemask Bottom")
		(5 "F.SilkS" user "Ref Des/Silkscreen Top")
		(7 "B.SilkS" user "Ref Des/Silkscreen Bottom")
		(1 "F.Mask" user "Board Geometry/Soldermask Top")
		(3 "B.Mask" user "Board Geometry/Soldermask Bottom")
		(17 "Dwgs.User" user "User.Drawings")
		(19 "Cmts.User" user "User.Comments")
		(21 "Eco1.User" user "User.Eco1")
		(23 "Eco2.User" user "User.Eco2")
		(25 "Edge.Cuts" user "Board Geometry/Outline")
		(27 "Margin" user)
		(31 "F.CrtYd" user "Package Geometry/Place Bound Top")
		(29 "B.CrtYd" user "Package Geometry/Place Bound Bottom")
		(35 "F.Fab" user "Ref Des/Assembly Top")
		(33 "B.Fab" user "Ref Des/Assembly Bottom")
	)
	(footprint ""
		(layer "F.Cu")
		(at 188.84392 -110.20806)
		(property "Reference" "R538"
			(at 0 0 0)
			(layer "F.SilkS")
			(hide yes)
			(effects
				(font
					(size 1.27 1.27)
				)
			)
		)
		(property "Value" "0R2J-2-GP"
			(at 0.064008 -3.993896 0)
			(unlocked yes)
			(layer "F.Fab")
			(hide yes)
			(effects
				(font
					(size 1.016 1.016)
					(thickness 0.1524)
				)
			)
		)
		(property "Device Type" "R402H16"
			(at 0.064008 -5.517896 0)
			(unlocked yes)
			(layer "F.Fab")
			(hide yes)
			(effects
				(font
					(size 1.016 1.016)
					(thickness 0.1524)
				)
			)
		)
		(duplicate_pad_numbers_are_jumpers no)
		(fp_line
			(start -0.508 -0.9398)
			(end -0.508 0.9398)
			(stroke
				(width 0.1524)
				(type default)
			)
			(layer "F.SilkS")
		)
		(fp_line
			(start 0.508 -0.9398)
			(end -0.508 -0.9398)
			(stroke
				(width 0.1524)
				(type default)
			)
			(layer "F.SilkS")
		)
		(fp_rect
			(start -0.508 0.9398)
			(end 0.508 -0.9398)
			(stroke
				(width 0)
				(type default)
			)
			(fill no)
			(layer "F.CrtYd")
		)
		(fp_rect
			(start -0.508 0.9398)
			(end 0.508 -0.9398)
			(stroke
				(width 0)
				(type default)
			)
			(fill no)
			(layer "F.Fab")
		)
		(pad "1" smd custom
			(at 0 -0.4445)
			(size 0.1397 0.1397)
			(layers "F.Cu" "F.Mask" "F.Paste")
			(net "P0V9_PG")
			(options
				(clearance outline)
				(anchor circle)
			)
			(primitives
				(gr_poly
					(pts
						(arc
							(start -0.1778 -0.2794)
							(mid -0.249642 -0.249642)
							(end -0.2794 -0.1778)
						)
						(arc
							(start -0.2794 0.1778)
							(mid -0.249642 0.249642)
							(end -0.1778 0.2794)
						)
						(arc
							(start 0.1778 0.2794)
							(mid 0.249642 0.249642)
							(end 0.2794 0.1778)
						)
						(arc
							(start 0.2794 -0.1778)
							(mid 0.249642 -0.249642)
							(end 0.1778 -0.2794)
						)
					)
					(width 0)
					(fill yes)
				)
			)
		)
		(pad "2" smd custom
			(at 0 0.4445)
			(size 0.1397 0.1397)
			(layers "F.Cu" "F.Mask" "F.Paste")
			(net "P1V8_C_S")
			(options
				(clearance outline)
				(anchor circle)
			)
			(primitives
				(gr_poly
					(pts
						(arc
							(start -0.1778 -0.2794)
							(mid -0.249642 -0.249642)
							(end -0.2794 -0.1778)
						)
						(arc
							(start -0.2794 0.1778)
							(mid -0.249642 0.249642)
							(end -0.1778 0.2794)
						)
						(arc
							(start 0.1778 0.2794)
							(mid 0.249642 0.249642)
							(end 0.2794 0.1778)
						)
						(arc
							(start 0.2794 -0.1778)
							(mid 0.249642 -0.249642)
							(end 0.1778 -0.2794)
						)
					)
					(width 0)
					(fill yes)
				)
			)
		)
	)
	(footprint ""
		(layer "F.Cu")
		(at 17.907 -59.1312)
		(property "Reference" "R579"
			(at 0 0 0)
			(layer "F.SilkS")
			(hide yes)
			(effects
				(font
					(size 1.27 1.27)
				)
			)
		)
		(property "Value" "0R2J-2-GP"
			(at 0.064008 -3.993896 0)
			(unlocked yes)
			(layer "F.Fab")
			(hide yes)
			(effects
				(font
					(size 1.016 1.016)
					(thickness 0.1524)
				)
			)
		)
		(property "Device Type" "R402H16"
			(at 0.064008 -5.517896 0)
			(unlocked yes)
			(layer "F.Fab")
			(hide yes)
			(effects
				(font
					(size 1.016 1.016)
					(thickness 0.1524)
				)
			)
		)
		(duplicate_pad_numbers_are_jumpers no)
		(fp_line
			(start -0.508 -0.9398)
			(end -0.508 0.9398)
			(stroke
				(width 0.1524)
				(type default)
			)
			(layer "F.SilkS")
		)
		(fp_line
			(start 0.508 -0.9398)
			(end -0.508 -0.9398)
			(stroke
				(width 0.1524)
				(type default)
			)
			(layer "F.SilkS")
		)
		(fp_rect
			(start -0.508 0.9398)
			(end 0.508 -0.9398)
			(stroke
				(width 0)
				(type default)
			)
			(fill no)
			(layer "F.CrtYd")
		)
		(fp_rect
			(start -0.508 0.9398)
			(end 0.508 -0.9398)
			(stroke
				(width 0)
				(type default)
			)
			(fill no)
			(layer "F.Fab")
		)
		(pad "1" smd custom
			(at 0 -0.4445)
			(size 0.1397 0.1397)
			(layers "F.Cu" "F.Mask" "F.Paste")
			(net "AGND_CURRENT_MON")
			(options
				(clearance outline)
				(anchor circle)
			)
			(primitives
				(gr_poly
					(pts
						(arc
							(start -0.1778 -0.2794)
							(mid -0.249642 -0.249642)
							(end -0.2794 -0.1778)
						)
						(arc
							(start -0.2794 0.1778)
							(mid -0.249642 0.249642)
							(end -0.1778 0.2794)
						)
						(arc
							(start 0.1778 0.2794)
							(mid 0.249642 0.249642)
							(end 0.2794 0.1778)
						)
						(arc
							(start 0.2794 -0.1778)
							(mid 0.249642 -0.249642)
							(end 0.1778 -0.2794)
						)
					)
					(width 0)
					(fill yes)
				)
			)
		)
		(pad "2" smd custom
			(at 0 0.4445)
			(size 0.1397 0.1397)
			(layers "F.Cu" "F.Mask" "F.Paste")
			(net "MB0_CM_ADR2_R")
			(options
				(clearance outline)
				(anchor circle)
			)
			(primitives
				(gr_poly
					(pts
						(arc
							(start -0.1778 -0.2794)
							(mid -0.249642 -0.249642)
							(end -0.2794 -0.1778)
						)
						(arc
							(start -0.2794 0.1778)
							(mid -0.249642 0.249642)
							(end -0.1778 0.2794)
						)
						(arc
							(start 0.1778 0.2794)
							(mid 0.249642 0.249642)
							(end 0.2794 0.1778)
						)
						(arc
							(start 0.2794 -0.1778)
							(mid 0.249642 -0.249642)
							(end 0.1778 -0.2794)
						)
					)
					(width 0)
					(fill yes)
				)
			)
		)
	)
	(footprint ""
		(layer "F.Cu")
		(at 181.580282 -102.365556 90)
		(property "Reference" "C394"
			(at 0 0 90)
			(layer "F.SilkS")
			(hide yes)
			(effects
				(font
					(size 1.27 1.27)
				)
			)
		)
		(property "Value" "SC100U6D3V6MX-GP"
			(at -0.0762 -5.1308 90)
			(unlocked yes)
			(layer "F.Fab")
			(hide yes)
			(effects
				(font
					(size 1.016 1.016)
					(thickness 0.1524)
				)
			)
		)
		(property "Device Type" "C1206H71"
			(at -0.127 -6.6548 90)
			(unlocked yes)
			(layer "F.Fab")
			(hide yes)
			(effects
				(font
					(size 1.016 1.016)
					(thickness 0.1524)
				)
			)
		)
		(duplicate_pad_numbers_are_jumpers no)
		(fp_line
			(start 1.016 -2.2352)
			(end 1.016 -0.8382)
			(stroke
				(width 0.1524)
				(type default)
			)
			(layer "F.SilkS")
		)
		(fp_line
			(start -1.016 -2.2352)
			(end 1.016 -2.2352)
			(stroke
				(width 0.1524)
				(type default)
			)
			(layer "F.SilkS")
		)
		(fp_line
			(start -1.016 -0.8382)
			(end -1.016 -2.2352)
			(stroke
				(width 0.1524)
				(type default)
			)
			(layer "F.SilkS")
		)
		(fp_line
			(start 1.016 0.8382)
			(end 1.016 2.2352)
			(stroke
				(width 0.1524)
				(type default)
			)
			(layer "F.SilkS")
		)
		(fp_line
			(start 1.016 2.2352)
			(end -1.016 2.2352)
			(stroke
				(width 0.1524)
				(type default)
			)
			(layer "F.SilkS")
		)
		(fp_line
			(start -1.016 2.2352)
			(end -1.016 0.8382)
			(stroke
				(width 0.1524)
				(type default)
			)
			(layer "F.SilkS")
		)
		(fp_rect
			(start -1.0922 2.3114)
			(end 1.0922 -2.3114)
			(stroke
				(width 0)
				(type default)
			)
			(fill no)
			(layer "F.CrtYd")
		)
		(fp_poly
			(pts
				(xy 1.0922 -2.3114) (xy 1.0922 2.3114) (xy -1.0922 2.3114) (xy -1.0922 -2.3114)
			)
			(stroke
				(width 0)
				(type default)
			)
			(fill no)
			(layer "F.Fab")
		)
		(pad "1" smd rect
			(at 0 -1.397 90)
			(size 1.651 1.27)
			(layers "F.Cu" "F.Mask" "F.Paste")
			(net "GND")
		)
		(pad "2" smd rect
			(at 0 1.397 90)
			(size 1.651 1.27)
			(layers "F.Cu" "F.Mask" "F.Paste")
			(net "SAS0_AVDD")
		)
	)
	(footprint ""
		(layer "F.Cu")
		(at 7.0866 -56.769 90)
		(property "Reference" "R487"
			(at 0 0 90)
			(layer "F.SilkS")
			(hide yes)
			(effects
				(font
					(size 1.27 1.27)
				)
			)
		)
		(property "Value" "10KR2F-2-GP"
			(at 0.064008 -3.993896 90)
			(unlocked yes)
			(layer "F.Fab")
			(hide yes)
			(effects
				(font
					(size 1.016 1.016)
					(thickness 0.1524)
				)
			)
		)
		(property "Device Type" "R402H16"
			(at 0.064008 -5.517896 90)
			(unlocked yes)
			(layer "F.Fab")
			(hide yes)
			(effects
				(font
					(size 1.016 1.016)
					(thickness 0.1524)
				)
			)
		)
		(duplicate_pad_numbers_are_jumpers no)
		(fp_line
			(start 0.508 -0.9398)
			(end -0.508 -0.9398)
			(stroke
				(width 0.1524)
				(type default)
			)
			(layer "F.SilkS")
		)
		(fp_line
			(start -0.508 -0.9398)
			(end -0.508 0.9398)
			(stroke
				(width 0.1524)
				(type default)
			)
			(layer "F.SilkS")
		)
		(fp_rect
			(start -0.508 0.9398)
			(end 0.508 -0.9398)
			(stroke
				(width 0)
				(type default)
			)
			(fill no)
			(layer "F.CrtYd")
		)
		(fp_rect
			(start -0.508 0.9398)
			(end 0.508 -0.9398)
			(stroke
				(width 0)
				(type default)
			)
			(fill no)
			(layer "F.Fab")
		)
		(pad "1" smd custom
			(at 0 -0.4445 90)
			(size 0.1397 0.1397)
			(layers "F.Cu" "F.Mask" "F.Paste")
			(net "GND")
			(options
				(clearance outline)
				(anchor circle)
			)
			(primitives
				(gr_poly
					(pts
						(arc
							(start -0.1778 -0.2794)
							(mid -0.249642 -0.249642)
							(end -0.2794 -0.1778)
						)
						(arc
							(start -0.2794 0.1778)
							(mid -0.249642 0.249642)
							(end -0.1778 0.2794)
						)
						(arc
							(start 0.1778 0.2794)
							(mid 0.249642 0.249642)
							(end 0.2794 0.1778)
						)
						(arc
							(start 0.2794 -0.1778)
							(mid 0.249642 -0.249642)
							(end 0.1778 -0.2794)
						)
					)
					(width 0)
					(fill yes)
				)
			)
		)
		(pad "2" smd custom
			(at 0 0.4445 90)
			(size 0.1397 0.1397)
			(layers "F.Cu" "F.Mask" "F.Paste")
			(net "P12V_SCC_PGOOD")
			(options
				(clearance outline)
				(anchor circle)
			)
			(primitives
				(gr_poly
					(pts
						(arc
							(start -0.1778 -0.2794)
							(mid -0.249642 -0.249642)
							(end -0.2794 -0.1778)
						)
						(arc
							(start -0.2794 0.1778)
							(mid -0.249642 0.249642)
							(end -0.1778 0.2794)
						)
						(arc
							(start 0.1778 0.2794)
							(mid 0.249642 0.249642)
							(end 0.2794 0.1778)
						)
						(arc
							(start 0.2794 -0.1778)
							(mid 0.249642 -0.249642)
							(end 0.1778 -0.2794)
						)
					)
					(width 0)
					(fill yes)
				)
			)
		)
	)
	(footprint ""
		(layer "F.Cu")
		(at 169.336974 -101.646482 90)
		(property "Reference" "R493"
			(at 0 0 90)
			(layer "F.SilkS")
			(hide yes)
			(effects
				(font
					(size 1.27 1.27)
				)
			)
		)
		(property "Value" "453R2F-1-GP"
			(at 0.064008 -3.993896 90)
			(unlocked yes)
			(layer "F.Fab")
			(hide yes)
			(effects
				(font
					(size 1.016 1.016)
					(thickness 0.1524)
				)
			)
		)
		(property "Device Type" "R402H16"
			(at 0.064008 -5.517896 90)
			(unlocked yes)
			(layer "F.Fab")
			(hide yes)
			(effects
				(font
					(size 1.016 1.016)
					(thickness 0.1524)
				)
			)
		)
		(duplicate_pad_numbers_are_jumpers no)
		(fp_line
			(start 0.508 -0.9398)
			(end -0.508 -0.9398)
			(stroke
				(width 0.1524)
				(type default)
			)
			(layer "F.SilkS")
		)
		(fp_line
			(start -0.508 -0.9398)
			(end -0.508 0.9398)
			(stroke
				(width 0.1524)
				(type default)
			)
			(layer "F.SilkS")
		)
		(fp_rect
			(start -0.508 0.9398)
			(end 0.508 -0.9398)
			(stroke
				(width 0)
				(type default)
			)
			(fill no)
			(layer "F.CrtYd")
		)
		(fp_rect
			(start -0.508 0.9398)
			(end 0.508 -0.9398)
			(stroke
				(width 0)
				(type default)
			)
			(fill no)
			(layer "F.Fab")
		)
		(pad "1" smd custom
			(at 0 -0.4445 90)
			(size 0.1397 0.1397)
			(layers "F.Cu" "F.Mask" "F.Paste")
			(net "VT235_VDES_RR")
			(options
				(clearance outline)
				(anchor circle)
			)
			(primitives
				(gr_poly
					(pts
						(arc
							(start -0.1778 -0.2794)
							(mid -0.249642 -0.249642)
							(end -0.2794 -0.1778)
						)
						(arc
							(start -0.2794 0.1778)
							(mid -0.249642 0.249642)
							(end -0.1778 0.2794)
						)
						(arc
							(start 0.1778 0.2794)
							(mid 0.249642 0.249642)
							(end 0.2794 0.1778)
						)
						(arc
							(start 0.2794 -0.1778)
							(mid 0.249642 -0.249642)
							(end 0.1778 -0.2794)
						)
					)
					(width 0)
					(fill yes)
				)
			)
		)
		(pad "2" smd custom
			(at 0 0.4445 90)
			(size 0.1397 0.1397)
			(layers "F.Cu" "F.Mask" "F.Paste")
			(net "VT235_VDES_RCC")
			(options
				(clearance outline)
				(anchor circle)
			)
			(primitives
				(gr_poly
					(pts
						(arc
							(start -0.1778 -0.2794)
							(mid -0.249642 -0.249642)
							(end -0.2794 -0.1778)
						)
						(arc
							(start -0.2794 0.1778)
							(mid -0.249642 0.249642)
							(end -0.1778 0.2794)
						)
						(arc
							(start 0.1778 0.2794)
							(mid 0.249642 0.249642)
							(end 0.2794 0.1778)
						)
						(arc
							(start 0.2794 -0.1778)
							(mid 0.249642 -0.249642)
							(end 0.1778 -0.2794)
						)
					)
					(width 0)
					(fill yes)
				)
			)
		)
	)
	(footprint ""
		(layer "F.Cu")
		(at 7.2898 -73.0758 -90)
		(property "Reference" "R363"
			(at 0 0 270)
			(layer "F.SilkS")
			(hide yes)
			(effects
				(font
					(size 1.27 1.27)
				)
			)
		)
		(property "Value" "4K7R2F-GP"
			(at 0.064008 -3.993896 270)
			(unlocked yes)
			(layer "F.Fab")
			(hide yes)
			(effects
				(font
					(size 1.016 1.016)
					(thickness 0.1524)
				)
			)
		)
		(property "Device Type" "R402H16"
			(at 0.064008 -5.517896 270)
			(unlocked yes)
			(layer "F.Fab")
			(hide yes)
			(effects
				(font
					(size 1.016 1.016)
					(thickness 0.1524)
				)
			)
		)
		(duplicate_pad_numbers_are_jumpers no)
		(fp_line
			(start -0.508 -0.9398)
			(end -0.508 0.9398)
			(stroke
				(width 0.1524)
				(type default)
			)
			(layer "F.SilkS")
		)
		(fp_line
			(start 0.508 -0.9398)
			(end -0.508 -0.9398)
			(stroke
				(width 0.1524)
				(type default)
			)
			(layer "F.SilkS")
		)
		(fp_rect
			(start -0.508 0.9398)
			(end 0.508 -0.9398)
			(stroke
				(width 0)
				(type default)
			)
			(fill no)
			(layer "F.CrtYd")
		)
		(fp_rect
			(start -0.508 0.9398)
			(end 0.508 -0.9398)
			(stroke
				(width 0)
				(type default)
			)
			(fill no)
			(layer "F.Fab")
		)
		(pad "1" smd custom
			(at 0 -0.4445 270)
			(size 0.1397 0.1397)
			(layers "F.Cu" "F.Mask" "F.Paste")
			(net "FRU_EEPROM_A1")
			(options
				(clearance outline)
				(anchor circle)
			)
			(primitives
				(gr_poly
					(pts
						(arc
							(start -0.1778 -0.2794)
							(mid -0.249642 -0.249642)
							(end -0.2794 -0.1778)
						)
						(arc
							(start -0.2794 0.1778)
							(mid -0.249642 0.249642)
							(end -0.1778 0.2794)
						)
						(arc
							(start 0.1778 0.2794)
							(mid 0.249642 0.249642)
							(end 0.2794 0.1778)
						)
						(arc
							(start 0.2794 -0.1778)
							(mid 0.249642 -0.249642)
							(end 0.1778 -0.2794)
						)
					)
					(width 0)
					(fill yes)
				)
			)
		)
		(pad "2" smd custom
			(at 0 0.4445 270)
			(size 0.1397 0.1397)
			(layers "F.Cu" "F.Mask" "F.Paste")
			(net "GND")
			(options
				(clearance outline)
				(anchor circle)
			)
			(primitives
				(gr_poly
					(pts
						(arc
							(start -0.1778 -0.2794)
							(mid -0.249642 -0.249642)
							(end -0.2794 -0.1778)
						)
						(arc
							(start -0.2794 0.1778)
							(mid -0.249642 0.249642)
							(end -0.1778 0.2794)
						)
						(arc
							(start 0.1778 0.2794)
							(mid 0.249642 0.249642)
							(end 0.2794 0.1778)
						)
						(arc
							(start 0.2794 -0.1778)
							(mid 0.249642 -0.249642)
							(end 0.1778 -0.2794)
						)
					)
					(width 0)
					(fill yes)
				)
			)
		)
	)
	(footprint ""
		(layer "F.Cu")
		(at 19.05127 -89.104978)
		(property "Reference" "U35"
			(at 0 0 0)
			(layer "F.SilkS")
			(hide yes)
			(effects
				(font
					(size 1.27 1.27)
				)
			)
		)
		(property "Value" "PCA9306DCTR-GP"
			(at 0 -11.6332 0)
			(unlocked yes)
			(layer "F.Fab")
			(hide yes)
			(effects
				(font
					(size 1.016 1.016)
					(thickness 0.1524)
				)
			)
		)
		(property "Device Type" "SSOIC8H52"
			(at 0 -13.1572 0)
			(unlocked yes)
			(layer "F.Fab")
			(hide yes)
			(effects
				(font
					(size 1.016 1.016)
					(thickness 0.1524)
				)
			)
		)
		(duplicate_pad_numbers_are_jumpers no)
		(fp_line
			(start -1.7018 -0.5842)
			(end -1.7018 2.286)
			(stroke
				(width 0.1524)
				(type default)
			)
			(layer "F.SilkS")
		)
		(fp_line
			(start -1.7018 -0.5842)
			(end 1.0668 -0.5842)
			(stroke
				(width 0.1524)
				(type default)
			)
			(layer "F.SilkS")
		)
		(fp_line
			(start -1.524 0.5842)
			(end -1.524 2.286)
			(stroke
				(width 0.508)
				(type default)
			)
			(layer "F.SilkS")
		)
		(fp_line
			(start -1.397 0)
			(end -1.7018 -0.3048)
			(stroke
				(width 0.1524)
				(type default)
			)
			(layer "F.SilkS")
		)
		(fp_line
			(start -1.397 0)
			(end -1.7018 0.3048)
			(stroke
				(width 0.1524)
				(type default)
			)
			(layer "F.SilkS")
		)
		(fp_line
			(start 1.0668 -0.5842)
			(end 1.0668 0.5842)
			(stroke
				(width 0.1524)
				(type default)
			)
			(layer "F.SilkS")
		)
		(fp_line
			(start 1.0668 0.5842)
			(end -1.524 0.5842)
			(stroke
				(width 0.1524)
				(type default)
			)
			(layer "F.SilkS")
		)
		(fp_poly
			(pts
				(xy -1.1684 -0.5842) (xy 1.0668 -0.5842) (xy 1.0668 0.5842) (xy -1.1684 0.5842)
			)
			(stroke
				(width 0)
				(type default)
			)
			(fill yes)
			(layer "F.SilkS")
		)
		(fp_poly
			(pts
				(xy -1.778 2.54) (xy 1.778 2.54) (xy 1.778 -2.54) (xy -1.778 -2.54)
			)
			(stroke
				(width 0)
				(type default)
			)
			(fill no)
			(layer "F.CrtYd")
		)
		(fp_poly
			(pts
				(xy -1.778 -2.54) (xy 1.778 -2.54) (xy 1.778 2.54) (xy -1.778 2.54)
			)
			(stroke
				(width 0)
				(type default)
			)
			(fill no)
			(layer "F.Fab")
		)
		(pad "1" smd rect
			(at -0.97536 1.6256)
			(size 0.3556 1.524)
			(layers "F.Cu" "F.Mask" "F.Paste")
			(net "GND")
		)
		(pad "2" smd rect
			(at -0.32512 1.6256)
			(size 0.3556 1.524)
			(layers "F.Cu" "F.Mask" "F.Paste")
			(net "P1V8_E")
		)
		(pad "3" smd rect
			(at 0.32512 1.6256)
			(size 0.3556 1.524)
			(layers "F.Cu" "F.Mask" "F.Paste")
			(net "I2C_BMC_LOC_SCL0_LS")
		)
		(pad "4" smd rect
			(at 0.97536 1.6256)
			(size 0.3556 1.524)
			(layers "F.Cu" "F.Mask" "F.Paste")
			(net "I2C_BMC_LOC_SDA0_LS")
		)
		(pad "5" smd rect
			(at 0.97536 -1.6256)
			(size 0.3556 1.524)
			(layers "F.Cu" "F.Mask" "F.Paste")
			(net "I2C_BMC_LOC_SDA0")
		)
		(pad "6" smd rect
			(at 0.32512 -1.6256)
			(size 0.3556 1.524)
			(layers "F.Cu" "F.Mask" "F.Paste")
			(net "I2C_BMC_LOC_SCL0")
		)
		(pad "7" smd rect
			(at -0.32512 -1.6256)
			(size 0.3556 1.524)
			(layers "F.Cu" "F.Mask" "F.Paste")
			(net "VREF0")
		)
		(pad "8" smd rect
			(at -0.97536 -1.6256)
			(size 0.3556 1.524)
			(layers "F.Cu" "F.Mask" "F.Paste")
			(net "LS_EN_U35")
		)
	)
)
